#ISCELL
  mstr_misc dns *
  *
#ISCELL
  pure_quanta quanta_title_block_c *
  *
#CELL
  pure_quanta q_res *
  page307_i12
#ISCELL
  logical_power universal_gnd *
  page307_i14
#CELL
  pure_quanta q_res *
  page307_i15
#CELL
  pure_quanta q_cap *
  page307_i17
#ISCELL
  logical_power universal_gnd *
  page307_i18
#ISCELL
  logical_power universal_power *
  page307_i19
#ISCELL
  standard offpage *
  page307_i20
#ISCELL
  standard offpage *
  page307_i21
#ISCELL
  standard offpage *
  page307_i22
#ISCELL
  standard offpage *
  page307_i23
#ISCELL
  logical_power universal_gnd *
  page307_i24
#ISCELL
  logical_power universal_gnd *
  page307_i25
#ISCELL
  logical_power universal_power *
  page307_i26
#ISCELL
  standard offpage *
  page307_i27
#ISCELL
  standard offpage *
  page307_i28
#ISCELL
  standard offpage *
  page307_i29
#ISCELL
  standard offpage *
  page307_i3
#ISCELL
  standard offpage *
  page307_i30
#ISCELL
  logical_power universal_gnd *
  page307_i31
#CELL
  pure_quanta 74cbtlv3126pw *
  page307_i32
#CELL
  pure_quanta q_cap *
  page307_i33
#ISCELL
  logical_power universal_gnd *
  page307_i34
#ISCELL
  logical_power universal_power *
  page307_i35
#CELL
  pure_quanta q_res *
  page307_i37
#CELL
  pure_quanta q_res *
  page307_i38
#ISCELL
  logical_power universal_gnd *
  page307_i39
#CELL
  pure_quanta q_res *
  page307_i40
#ISCELL
  standard offpage *
  page307_i44
#ISCELL
  standard offpage *
  page307_i45
#ISCELL
  standard offpage *
  page307_i46
#CELL
  pure_quanta q_res *
  page307_i56
#CELL
  pure_quanta q_res *
  page307_i60
#CELL
  pure_quanta q_res *
  page307_i61
#CELL
  pure_quanta q_res *
  page307_i62
#CELL
  pure_quanta q_res *
  page307_i63
#CELL
  pure_quanta q_res *
  page307_i64
#CELL
  pure_quanta q_res *
  page307_i65
#ISCELL
  standard offpage *
  page307_i66
#ISCELL
  standard offpage *
  page307_i67
#ISCELL
  standard offpage *
  page307_i68
#ISCELL
  standard offpage *
  page307_i69
#ISCELL
  standard offpage *
  page307_i73
#ISCELL
  standard offpage *
  page307_i74
#ISCELL
  standard offpage *
  page307_i75
#ISCELL
  standard offpage *
  page307_i76
#CELL
  pure_quanta q_cap *
  page307_i77
#CELL
  pure_quanta 74cbtlv3126pw *
  page307_i78
#CELL
  pure_quanta q_res *
  page307_i79
#CELL
  pure_quanta 74lvc1g126se7 *
  page307_i80
#CELL
  pure_quanta q_res *
  page307_i81
#ISCELL
  standard offpage *
  page307_i82
#ISCELL
  logical_power universal_gnd *
  page307_i83
#ISCELL
  standard offpage *
  page307_i84
#CELL
  pure_quanta q_res *
  page307_i85
#ISCELL
  standard offpage *
  page307_i9
